# BASEBOARD_FAB2 (Tioga Pass) — schematic netlist excerpt (pin names and nets, part order shuffled) for the footprints in the layout excerpt that follows; sources: Cadence DE-HDL packaged netlist, KiCad conversion of Wiwynn_Tioga_Pass_MB.brd

C3P22  CAP  0.22UF 16V 10% X7R  pkg 0402  page 107 : A = P3E_CPU0_PE1_SS_TXP<3> ; B = P3E_CPU0_PE1_SS_C_TXP<3>
C9E12  CAP_A  22.0UF 4V 20% EMPTY  pkg 0603V  page 139 : A = P0V9_LAN ; B = GND
C6U11  CAP  4.7UF 6.3V 10% X6S  pkg 0603  page 229 : A = VSENSE_PVDDQ_GHJ_VTT ; B = GND

(kicad_pcb
	(version 20260206)
	(generator "pcbnew")
	(generator_version "10.0")
	(general
		(thickness 1.6)
		(legacy_teardrops no)
	)
	(paper "A4")
	(title_block
		(title "Wiwynn_Tioga_Pass_MB.brd")
		(comment 1 "Tioga Pass / footprints 2893-2895 of 4770")
	)
	(layers
		(0 "F.Cu" signal "TOP")
		(4 "In1.Cu" signal "L2GND")
		(6 "In2.Cu" signal "L3")
		(8 "In3.Cu" signal "L4GND")
		(10 "In4.Cu" signal "L5")
		(12 "In5.Cu" signal "L6GND")
		(14 "In6.Cu" signal "L7VCC")
		(16 "In7.Cu" signal "L8VCC")
		(18 "In8.Cu" signal "L9GND")
		(20 "In9.Cu" signal "L10")
		(22 "In10.Cu" signal "L11GND")
		(24 "In11.Cu" signal "L12")
		(26 "In12.Cu" signal "L13GND")
		(2 "B.Cu" signal "BOTTOM")
		(9 "F.Adhes" user "F.Adhesive")
		(11 "B.Adhes" user "B.Adhesive")
		(13 "F.Paste" user "Package Geometry/Pastemask Top")
		(15 "B.Paste" user "Package Geometry/Pastemask Bottom")
		(5 "F.SilkS" user "Ref Des/Silkscreen Top")
		(7 "B.SilkS" user "Ref Des/Silkscreen Bottom")
		(1 "F.Mask" user "Board Geometry/Soldermask Top")
		(3 "B.Mask" user "Board Geometry/Soldermask Bottom")
		(17 "Dwgs.User" user "User.Drawings")
		(19 "Cmts.User" user "User.Comments")
		(21 "Eco1.User" user "User.Eco1")
		(23 "Eco2.User" user "User.Eco2")
		(25 "Edge.Cuts" user "Board Geometry/Outline")
		(27 "Margin" user)
		(31 "F.CrtYd" user "Package Geometry/Place Bound Top")
		(29 "B.CrtYd" user "Package Geometry/Place Bound Bottom")
		(35 "F.Fab" user "Ref Des/Assembly Top")
		(33 "B.Fab" user "Ref Des/Assembly Bottom")
	)
	(footprint ""
		(layer "B.Cu")
		(at 173.4947 -5.551424 -90)
		(property "Reference" "C6U11"
			(at 0 0 90)
			(layer "B.SilkS")
			(hide yes)
			(effects
				(font
					(size 1.27 1.27)
				)
				(justify mirror)
			)
		)
		(property "Value" ""
			(at 0 0 90)
			(layer "B.Fab")
			(effects
				(font
					(size 1.27 1.27)
				)
				(justify mirror)
			)
		)
		(duplicate_pad_numbers_are_jumpers no)
		(fp_poly
			(pts
				(xy 0.4953 -0.2032) (xy -0.4953 -0.2032) (xy -0.4953 1.6002) (xy 0.4953 1.6002)
			)
			(stroke
				(width 0)
				(type default)
			)
			(fill no)
			(layer "B.CrtYd")
		)
		(fp_line
			(start -0.4953 1.6002)
			(end 0.4953 1.6002)
			(stroke
				(width 0.1)
				(type default)
			)
			(layer "B.Fab")
		)
		(fp_line
			(start 0.4953 1.6002)
			(end 0.4953 -0.2032)
			(stroke
				(width 0.1)
				(type default)
			)
			(layer "B.Fab")
		)
		(fp_line
			(start -0.4953 -0.2032)
			(end -0.4953 1.6002)
			(stroke
				(width 0.1)
				(type default)
			)
			(layer "B.Fab")
		)
		(fp_line
			(start 0.4953 -0.2032)
			(end -0.4953 -0.2032)
			(stroke
				(width 0.1)
				(type default)
			)
			(layer "B.Fab")
		)
		(pad "1" smd rect
			(at 0 0 90)
			(size 0.762 0.889)
			(layers "B.Cu" "B.Mask" "B.Paste")
			(net "VSENSE_PVDDQ_GHJ_VTT")
		)
		(pad "2" smd rect
			(at 0 1.397 90)
			(size 0.762 0.889)
			(layers "B.Cu" "B.Mask" "B.Paste")
			(net "GND")
		)
		(zone
			(layer "B.Cu")
			(hatch none 0.5)
			(connect_pads
				(clearance 0)
			)
			(min_thickness 0.25)
			(keepout
				(tracks not_allowed)
				(vias allowed)
				(pads allowed)
				(copperpour not_allowed)
				(footprints allowed)
			)
			(placement
				(enabled no)
				(sheetname "")
			)
			(fill
				(thermal_gap 0.5)
				(thermal_bridge_width 0.5)
				(island_removal_mode 0)
			)
			(polygon
				(pts
					(xy 173.0502 -5.170424) (xy 173.0502 -5.932424) (xy 172.5422 -5.932424) (xy 172.5422 -5.170424)
				)
			)
		)
	)
	(footprint ""
		(layer "B.Cu")
		(at 488.191302 -48.124872 -90)
		(property "Reference" "C9E12"
			(at 0 0 90)
			(layer "B.SilkS")
			(hide yes)
			(effects
				(font
					(size 1.27 1.27)
				)
				(justify mirror)
			)
		)
		(property "Value" ""
			(at 0 0 90)
			(layer "B.Fab")
			(effects
				(font
					(size 1.27 1.27)
				)
				(justify mirror)
			)
		)
		(duplicate_pad_numbers_are_jumpers no)
		(fp_poly
			(pts
				(xy 0.4953 -0.2032) (xy -0.4953 -0.2032) (xy -0.4953 1.6002) (xy 0.4953 1.6002)
			)
			(stroke
				(width 0)
				(type default)
			)
			(fill no)
			(layer "B.CrtYd")
		)
		(fp_line
			(start -0.4953 1.6002)
			(end 0.4953 1.6002)
			(stroke
				(width 0.1)
				(type default)
			)
			(layer "B.Fab")
		)
		(fp_line
			(start 0.4953 1.6002)
			(end 0.4953 -0.2032)
			(stroke
				(width 0.1)
				(type default)
			)
			(layer "B.Fab")
		)
		(fp_line
			(start -0.4953 -0.2032)
			(end -0.4953 1.6002)
			(stroke
				(width 0.1)
				(type default)
			)
			(layer "B.Fab")
		)
		(fp_line
			(start 0.4953 -0.2032)
			(end -0.4953 -0.2032)
			(stroke
				(width 0.1)
				(type default)
			)
			(layer "B.Fab")
		)
		(pad "1" smd rect
			(at 0 0 90)
			(size 0.762 0.889)
			(layers "B.Cu" "B.Mask" "B.Paste")
			(net "P0V9_LAN")
		)
		(pad "2" smd rect
			(at 0 1.397 90)
			(size 0.762 0.889)
			(layers "B.Cu" "B.Mask" "B.Paste")
			(net "GND")
		)
		(zone
			(layer "B.Cu")
			(hatch none 0.5)
			(connect_pads
				(clearance 0)
			)
			(min_thickness 0.25)
			(keepout
				(tracks not_allowed)
				(vias allowed)
				(pads allowed)
				(copperpour not_allowed)
				(footprints allowed)
			)
			(placement
				(enabled no)
				(sheetname "")
			)
			(fill
				(thermal_gap 0.5)
				(thermal_bridge_width 0.5)
				(island_removal_mode 0)
			)
			(polygon
				(pts
					(xy 487.746802 -47.743872) (xy 487.746802 -48.505872) (xy 487.238802 -48.505872) (xy 487.238802 -47.743872)
				)
			)
		)
	)
	(footprint ""
		(layer "B.Cu")
		(at 347.17736 -77.788516)
		(property "Reference" "C3P22"
			(at 0 0 0)
			(layer "B.SilkS")
			(hide yes)
			(effects
				(font
					(size 1.27 1.27)
				)
				(justify mirror)
			)
		)
		(property "Value" ""
			(at 0 0 0)
			(layer "B.Fab")
			(effects
				(font
					(size 1.27 1.27)
				)
				(justify mirror)
			)
		)
		(duplicate_pad_numbers_are_jumpers no)
		(fp_poly
			(pts
				(xy -0.3048 -0.1016) (xy -0.3048 0.9906) (xy 0.3048 0.9906) (xy 0.3048 -0.1016)
			)
			(stroke
				(width 0)
				(type default)
			)
			(fill no)
			(layer "B.CrtYd")
		)
		(fp_line
			(start -0.3048 -0.1016)
			(end 0.3048 -0.1016)
			(stroke
				(width 0.1)
				(type default)
			)
			(layer "B.Fab")
		)
		(fp_line
			(start -0.3048 0.9906)
			(end -0.3048 -0.1016)
			(stroke
				(width 0.1)
				(type default)
			)
			(layer "B.Fab")
		)
		(fp_line
			(start 0.3048 -0.1016)
			(end 0.3048 0.9906)
			(stroke
				(width 0.1)
				(type default)
			)
			(layer "B.Fab")
		)
		(fp_line
			(start 0.3048 0.9906)
			(end -0.3048 0.9906)
			(stroke
				(width 0.1)
				(type default)
			)
			(layer "B.Fab")
		)
		(pad "1" smd rect
			(at 0 0 180)
			(size 0.508 0.508)
			(layers "B.Cu" "B.Mask" "B.Paste")
			(net "P3E_CPU0_PE1_SS_TXP<3>")
		)
		(pad "2" smd rect
			(at 0 0.889 180)
			(size 0.508 0.508)
			(layers "B.Cu" "B.Mask" "B.Paste")
			(net "P3E_CPU0_PE1_SS_C_TXP<3>")
		)
		(zone
			(layer "B.Cu")
			(hatch none 0.5)
			(connect_pads
				(clearance 0)
			)
			(min_thickness 0.25)
			(keepout
				(tracks allowed)
				(vias not_allowed)
				(pads allowed)
				(copperpour not_allowed)
				(footprints allowed)
			)
			(placement
				(enabled no)
				(sheetname "")
			)
			(fill
				(thermal_gap 0.5)
				(thermal_bridge_width 0.5)
				(island_removal_mode 0)
			)
			(polygon
				(pts
					(xy 347.43136 -77.534516) (xy 346.92336 -77.534516) (xy 346.92336 -77.153516) (xy 347.43136 -77.153516)
				)
			)
		)
		(zone
			(layer "B.Cu")
			(hatch none 0.5)
			(connect_pads
				(clearance 0)
			)
			(min_thickness 0.25)
			(keepout
				(tracks not_allowed)
				(vias allowed)
				(pads allowed)
				(copperpour not_allowed)
				(footprints allowed)
			)
			(placement
				(enabled no)
				(sheetname "")
			)
			(fill
				(thermal_gap 0.5)
				(thermal_bridge_width 0.5)
				(island_removal_mode 0)
			)
			(polygon
				(pts
					(xy 347.43136 -77.153516) (xy 346.92336 -77.153516) (xy 346.92336 -77.534516) (xy 347.43136 -77.534516)
				)
			)
		)
	)
)
